# T6G (Grand Teton) — schematic netlist excerpt (pin names and nets, part order shuffled) for the footprints in the layout excerpt that follows; sources: Cadence DE-HDL packaged netlist, KiCad conversion of 04192023_DAF0TMB3IC0_F0TG_MB_C_brd_V02_OCP.brd

R1151  Q_RES  0 5% EMPTY  pkg 0402LF  page 160 : A = SMB_CPU0_CPU1_APML_BUF1_SCL_R1 ; B = SMB_CPU0_CPU1_APML_BUF1_SCL_R2
C486  Q_CAP  22UF 4V 20% X6S  pkg C0402  page 356 : A = P0V9_CPU1_RT3_2A ; B = GND
PC600_2  Q_CAP  22UF 4V 20% X6S  pkg C0805  page 198 : A = PVDDCR_SOC_P0 ; B = GND

(kicad_pcb
	(version 20260206)
	(generator "pcbnew")
	(generator_version "10.0")
	(general
		(thickness 1.6)
		(legacy_teardrops no)
	)
	(paper "A4")
	(title_block
		(title "04192023_DAF0TMB3IC0_F0TG_MB_C_brd_V02_OCP.brd")
		(comment 1 "Grand Teton / footprints 8291-8293 of 8354")
	)
	(layers
		(0 "F.Cu" signal "TOP")
		(4 "In1.Cu" signal "GND")
		(6 "In2.Cu" signal "IN1")
		(8 "In3.Cu" signal "GND1")
		(10 "In4.Cu" signal "IN2")
		(12 "In5.Cu" signal "GND2")
		(14 "In6.Cu" signal "IN3")
		(16 "In7.Cu" signal "GND3")
		(18 "In8.Cu" signal "VCC")
		(20 "In9.Cu" signal "VCC1")
		(22 "In10.Cu" signal "GND4")
		(24 "In11.Cu" signal "IN4")
		(26 "In12.Cu" signal "GND5")
		(28 "In13.Cu" signal "IN5")
		(30 "In14.Cu" signal "GND6")
		(32 "In15.Cu" signal "IN6")
		(34 "In16.Cu" signal "GND7")
		(2 "B.Cu" signal "BOTTOM")
		(9 "F.Adhes" user "F.Adhesive")
		(11 "B.Adhes" user "B.Adhesive")
		(13 "F.Paste" user "Package Geometry/Pastemask Top")
		(15 "B.Paste" user "Package Geometry/Pastemask Bottom")
		(5 "F.SilkS" user "Ref Des/Silkscreen Top")
		(7 "B.SilkS" user "Ref Des/Silkscreen Bottom")
		(1 "F.Mask" user "Board Geometry/Soldermask Top")
		(3 "B.Mask" user "Board Geometry/Soldermask Bottom")
		(17 "Dwgs.User" user "User.Drawings")
		(19 "Cmts.User" user "User.Comments")
		(21 "Eco1.User" user "User.Eco1")
		(23 "Eco2.User" user "User.Eco2")
		(25 "Edge.Cuts" user "Board Geometry/Outline")
		(27 "Margin" user)
		(31 "F.CrtYd" user "Package Geometry/Place Bound Top")
		(29 "B.CrtYd" user "Package Geometry/Place Bound Bottom")
		(35 "F.Fab" user "Ref Des/Assembly Top")
		(33 "B.Fab" user "Ref Des/Assembly Bottom")
	)
	(footprint ""
		(layer "B.Cu")
		(at 238.252 -217.678 90)
		(property "Reference" "R1151"
			(at 0 0 90)
			(layer "B.SilkS")
			(hide yes)
			(effects
				(font
					(size 1.27 1.27)
				)
				(justify mirror)
			)
		)
		(property "Value" ""
			(at 0 0 90)
			(layer "B.Fab")
			(effects
				(font
					(size 1.27 1.27)
				)
				(justify mirror)
			)
		)
		(duplicate_pad_numbers_are_jumpers no)
		(fp_line
			(start 0.7874 -0.4064)
			(end -0.7874 -0.4064)
			(stroke
				(width 0.1524)
				(type default)
			)
			(layer "B.SilkS")
		)
		(fp_line
			(start -0.7874 -0.4064)
			(end -0.7874 0.4064)
			(stroke
				(width 0.1524)
				(type default)
			)
			(layer "B.SilkS")
		)
		(fp_line
			(start 0.7874 0.4064)
			(end 0.7874 -0.4064)
			(stroke
				(width 0.1524)
				(type default)
			)
			(layer "B.SilkS")
		)
		(fp_line
			(start -0.7874 0.4064)
			(end 0.7874 0.4064)
			(stroke
				(width 0.1524)
				(type default)
			)
			(layer "B.SilkS")
		)
		(fp_line
			(start 0.67945 -0.305054)
			(end 0.12065 -0.305054)
			(stroke
				(width 0.1)
				(type default)
			)
			(layer "B.Fab")
		)
		(fp_line
			(start 0.12065 -0.305054)
			(end 0.12065 -0.2794)
			(stroke
				(width 0.1)
				(type default)
			)
			(layer "B.Fab")
		)
		(fp_line
			(start -0.12065 -0.3048)
			(end -0.67945 -0.3048)
			(stroke
				(width 0.1)
				(type default)
			)
			(layer "B.Fab")
		)
		(fp_line
			(start -0.67945 -0.3048)
			(end -0.67945 0.3048)
			(stroke
				(width 0.1)
				(type default)
			)
			(layer "B.Fab")
		)
		(fp_line
			(start 0.12065 -0.2794)
			(end -0.12065 -0.2794)
			(stroke
				(width 0.1)
				(type default)
			)
			(layer "B.Fab")
		)
		(fp_line
			(start -0.12065 -0.2794)
			(end -0.12065 -0.3048)
			(stroke
				(width 0.1)
				(type default)
			)
			(layer "B.Fab")
		)
		(fp_line
			(start 0.12065 0.2794)
			(end 0.12065 0.3048)
			(stroke
				(width 0.1)
				(type default)
			)
			(layer "B.Fab")
		)
		(fp_line
			(start -0.120396 0.2794)
			(end 0.12065 0.2794)
			(stroke
				(width 0.1)
				(type default)
			)
			(layer "B.Fab")
		)
		(fp_line
			(start 0.67945 0.3048)
			(end 0.67945 -0.305054)
			(stroke
				(width 0.1)
				(type default)
			)
			(layer "B.Fab")
		)
		(fp_line
			(start 0.12065 0.3048)
			(end 0.67945 0.3048)
			(stroke
				(width 0.1)
				(type default)
			)
			(layer "B.Fab")
		)
		(fp_line
			(start -0.120396 0.3048)
			(end -0.120396 0.2794)
			(stroke
				(width 0.1)
				(type default)
			)
			(layer "B.Fab")
		)
		(fp_line
			(start -0.67945 0.3048)
			(end -0.120396 0.3048)
			(stroke
				(width 0.1)
				(type default)
			)
			(layer "B.Fab")
		)
		(pad "1" smd circle
			(at 0.40005 0 270)
			(size 0 0)
			(layers "B.Cu" "B.Mask" "B.Paste")
			(net "SMB_CPU0_CPU1_APML_BUF1_SCL_R1")
		)
		(pad "2" smd circle
			(at -0.40005 0 270)
			(size 0 0)
			(layers "B.Cu" "B.Mask" "B.Paste")
			(net "SMB_CPU0_CPU1_APML_BUF1_SCL_R2")
		)
	)
	(footprint ""
		(layer "B.Cu")
		(at 133.8453 -390.560052 90)
		(property "Reference" "C486"
			(at 0 0 90)
			(layer "B.SilkS")
			(hide yes)
			(effects
				(font
					(size 1.27 1.27)
				)
				(justify mirror)
			)
		)
		(property "Value" ""
			(at 0 0 90)
			(layer "B.Fab")
			(effects
				(font
					(size 1.27 1.27)
				)
				(justify mirror)
			)
		)
		(duplicate_pad_numbers_are_jumpers no)
		(fp_line
			(start 0.7874 -0.4064)
			(end -0.7874 -0.4064)
			(stroke
				(width 0.1524)
				(type default)
			)
			(layer "B.SilkS")
		)
		(fp_line
			(start -0.7874 -0.4064)
			(end -0.7874 0.4064)
			(stroke
				(width 0.1524)
				(type default)
			)
			(layer "B.SilkS")
		)
		(fp_line
			(start 0.7874 0.4064)
			(end 0.7874 -0.4064)
			(stroke
				(width 0.1524)
				(type default)
			)
			(layer "B.SilkS")
		)
		(fp_line
			(start -0.7874 0.4064)
			(end 0.7874 0.4064)
			(stroke
				(width 0.1524)
				(type default)
			)
			(layer "B.SilkS")
		)
		(fp_line
			(start 0.67945 -0.305054)
			(end 0.12065 -0.305054)
			(stroke
				(width 0.1)
				(type default)
			)
			(layer "B.Fab")
		)
		(fp_line
			(start 0.12065 -0.305054)
			(end 0.12065 -0.2794)
			(stroke
				(width 0.1)
				(type default)
			)
			(layer "B.Fab")
		)
		(fp_line
			(start -0.12065 -0.3048)
			(end -0.67945 -0.3048)
			(stroke
				(width 0.1)
				(type default)
			)
			(layer "B.Fab")
		)
		(fp_line
			(start -0.67945 -0.3048)
			(end -0.67945 0.3048)
			(stroke
				(width 0.1)
				(type default)
			)
			(layer "B.Fab")
		)
		(fp_line
			(start 0.12065 -0.2794)
			(end -0.12065 -0.2794)
			(stroke
				(width 0.1)
				(type default)
			)
			(layer "B.Fab")
		)
		(fp_line
			(start -0.12065 -0.2794)
			(end -0.12065 -0.3048)
			(stroke
				(width 0.1)
				(type default)
			)
			(layer "B.Fab")
		)
		(fp_line
			(start 0.12065 0.2794)
			(end 0.12065 0.3048)
			(stroke
				(width 0.1)
				(type default)
			)
			(layer "B.Fab")
		)
		(fp_line
			(start -0.120396 0.2794)
			(end 0.12065 0.2794)
			(stroke
				(width 0.1)
				(type default)
			)
			(layer "B.Fab")
		)
		(fp_line
			(start 0.67945 0.3048)
			(end 0.67945 -0.305054)
			(stroke
				(width 0.1)
				(type default)
			)
			(layer "B.Fab")
		)
		(fp_line
			(start 0.12065 0.3048)
			(end 0.67945 0.3048)
			(stroke
				(width 0.1)
				(type default)
			)
			(layer "B.Fab")
		)
		(fp_line
			(start -0.120396 0.3048)
			(end -0.120396 0.2794)
			(stroke
				(width 0.1)
				(type default)
			)
			(layer "B.Fab")
		)
		(fp_line
			(start -0.67945 0.3048)
			(end -0.120396 0.3048)
			(stroke
				(width 0.1)
				(type default)
			)
			(layer "B.Fab")
		)
		(pad "1" smd circle
			(at 0.40005 0 270)
			(size 0 0)
			(layers "B.Cu" "B.Mask" "B.Paste")
			(net "P0V9_CPU1_RT3_2A")
		)
		(pad "2" smd circle
			(at -0.40005 0 270)
			(size 0 0)
			(layers "B.Cu" "B.Mask" "B.Paste")
			(net "GND")
		)
	)
	(footprint ""
		(layer "B.Cu")
		(at 410.160216 -177.225452 90)
		(property "Reference" "PC600_2"
			(at 0 0 90)
			(layer "B.SilkS")
			(hide yes)
			(effects
				(font
					(size 1.27 1.27)
				)
				(justify mirror)
			)
		)
		(property "Value" ""
			(at 0 0 90)
			(layer "B.Fab")
			(effects
				(font
					(size 1.27 1.27)
				)
				(justify mirror)
			)
		)
		(duplicate_pad_numbers_are_jumpers no)
		(fp_line
			(start 1.524 -0.762)
			(end -1.524 -0.762)
			(stroke
				(width 0.1524)
				(type default)
			)
			(layer "B.SilkS")
		)
		(fp_line
			(start -1.524 -0.762)
			(end -1.524 0.762)
			(stroke
				(width 0.1524)
				(type default)
			)
			(layer "B.SilkS")
		)
		(fp_line
			(start 1.524 0.762)
			(end 1.524 -0.762)
			(stroke
				(width 0.1524)
				(type default)
			)
			(layer "B.SilkS")
		)
		(fp_line
			(start -1.524 0.762)
			(end 1.524 0.762)
			(stroke
				(width 0.1524)
				(type default)
			)
			(layer "B.SilkS")
		)
		(fp_line
			(start 1.1049 -0.724916)
			(end 1.1049 0.724916)
			(stroke
				(width 0.1)
				(type default)
			)
			(layer "B.Fab")
		)
		(fp_line
			(start -1.1049 -0.724916)
			(end 1.1049 -0.724916)
			(stroke
				(width 0.1)
				(type default)
			)
			(layer "B.Fab")
		)
		(fp_line
			(start 1.1049 0.724916)
			(end -1.1049 0.724916)
			(stroke
				(width 0.1)
				(type default)
			)
			(layer "B.Fab")
		)
		(fp_line
			(start -1.1049 0.724916)
			(end -1.1049 -0.724916)
			(stroke
				(width 0.1)
				(type default)
			)
			(layer "B.Fab")
		)
		(pad "1" smd rect
			(at 0.889 0 90)
			(size 1.016 1.27)
			(layers "B.Cu" "B.Mask" "B.Paste")
			(net "PVDDCR_SOC_P0")
		)
		(pad "2" smd rect
			(at -0.889 0 90)
			(size 1.016 1.27)
			(layers "B.Cu" "B.Mask" "B.Paste")
			(net "GND")
		)
	)
)
